G04*
G04 #@! TF.GenerationSoftware,Altium Limited,Altium Designer,22.4.2 (48)*
G04*
G04 Layer_Color=16711935*
%FSLAX25Y25*%
%MOIN*%
G70*
G04*
G04 #@! TF.SameCoordinates,446674BB-F454-490D-8607-5140536C8ADF*
G04*
G04*
G04 #@! TF.FilePolarity,Positive*
G04*
G01*
G75*
M02*
